# T6G (Grand Teton) — schematic netlist excerpt (pin names and nets, part order shuffled) for the footprints in the layout excerpt that follows; sources: Cadence DE-HDL packaged netlist, KiCad conversion of 04192023_DAF0TMB3IC0_F0TG_MB_C_brd_V02_OCP.brd

C644  Q_CAP  4.7UF 6.3V 20% X6S  pkg 0402  page 290 : A = P0V9_CPU0_RT1_2A ; B = GND
C30  Q_CAP  0.1UF 25V 10% X7R  pkg 0402  page 29 : A = P1V8_AUX ; B = GND

(kicad_pcb
	(version 20260206)
	(generator "pcbnew")
	(generator_version "10.0")
	(general
		(thickness 1.6)
		(legacy_teardrops no)
	)
	(paper "A4")
	(title_block
		(title "04192023_DAF0TMB3IC0_F0TG_MB_C_brd_V02_OCP.brd")
		(comment 1 "Grand Teton / footprints 7878-7879 of 8354")
	)
	(layers
		(0 "F.Cu" signal "TOP")
		(4 "In1.Cu" signal "GND")
		(6 "In2.Cu" signal "IN1")
		(8 "In3.Cu" signal "GND1")
		(10 "In4.Cu" signal "IN2")
		(12 "In5.Cu" signal "GND2")
		(14 "In6.Cu" signal "IN3")
		(16 "In7.Cu" signal "GND3")
		(18 "In8.Cu" signal "VCC")
		(20 "In9.Cu" signal "VCC1")
		(22 "In10.Cu" signal "GND4")
		(24 "In11.Cu" signal "IN4")
		(26 "In12.Cu" signal "GND5")
		(28 "In13.Cu" signal "IN5")
		(30 "In14.Cu" signal "GND6")
		(32 "In15.Cu" signal "IN6")
		(34 "In16.Cu" signal "GND7")
		(2 "B.Cu" signal "BOTTOM")
		(9 "F.Adhes" user "F.Adhesive")
		(11 "B.Adhes" user "B.Adhesive")
		(13 "F.Paste" user "Package Geometry/Pastemask Top")
		(15 "B.Paste" user "Package Geometry/Pastemask Bottom")
		(5 "F.SilkS" user "Ref Des/Silkscreen Top")
		(7 "B.SilkS" user "Ref Des/Silkscreen Bottom")
		(1 "F.Mask" user "Board Geometry/Soldermask Top")
		(3 "B.Mask" user "Board Geometry/Soldermask Bottom")
		(17 "Dwgs.User" user "User.Drawings")
		(19 "Cmts.User" user "User.Comments")
		(21 "Eco1.User" user "User.Eco1")
		(23 "Eco2.User" user "User.Eco2")
		(25 "Edge.Cuts" user "Board Geometry/Outline")
		(27 "Margin" user)
		(31 "F.CrtYd" user "Package Geometry/Place Bound Top")
		(29 "B.CrtYd" user "Package Geometry/Place Bound Bottom")
		(35 "F.Fab" user "Ref Des/Assembly Top")
		(33 "B.Fab" user "Ref Des/Assembly Bottom")
	)
	(footprint ""
		(layer "B.Cu")
		(at 399.057622 -204.232002)
		(property "Reference" "C30"
			(at 0 0 0)
			(layer "B.SilkS")
			(hide yes)
			(effects
				(font
					(size 1.27 1.27)
				)
				(justify mirror)
			)
		)
		(property "Value" ""
			(at 0 0 0)
			(layer "B.Fab")
			(effects
				(font
					(size 1.27 1.27)
				)
				(justify mirror)
			)
		)
		(duplicate_pad_numbers_are_jumpers no)
		(fp_line
			(start -0.7874 -0.4064)
			(end -0.7874 0.4064)
			(stroke
				(width 0.1524)
				(type default)
			)
			(layer "B.SilkS")
		)
		(fp_line
			(start -0.7874 0.4064)
			(end 0.7874 0.4064)
			(stroke
				(width 0.1524)
				(type default)
			)
			(layer "B.SilkS")
		)
		(fp_line
			(start 0.7874 -0.4064)
			(end -0.7874 -0.4064)
			(stroke
				(width 0.1524)
				(type default)
			)
			(layer "B.SilkS")
		)
		(fp_line
			(start 0.7874 0.4064)
			(end 0.7874 -0.4064)
			(stroke
				(width 0.1524)
				(type default)
			)
			(layer "B.SilkS")
		)
		(fp_line
			(start -0.67945 -0.3048)
			(end -0.67945 0.3048)
			(stroke
				(width 0.1)
				(type default)
			)
			(layer "B.Fab")
		)
		(fp_line
			(start -0.67945 0.3048)
			(end -0.120396 0.3048)
			(stroke
				(width 0.1)
				(type default)
			)
			(layer "B.Fab")
		)
		(fp_line
			(start -0.12065 -0.3048)
			(end -0.67945 -0.3048)
			(stroke
				(width 0.1)
				(type default)
			)
			(layer "B.Fab")
		)
		(fp_line
			(start -0.12065 -0.2794)
			(end -0.12065 -0.3048)
			(stroke
				(width 0.1)
				(type default)
			)
			(layer "B.Fab")
		)
		(fp_line
			(start -0.120396 0.2794)
			(end 0.12065 0.2794)
			(stroke
				(width 0.1)
				(type default)
			)
			(layer "B.Fab")
		)
		(fp_line
			(start -0.120396 0.3048)
			(end -0.120396 0.2794)
			(stroke
				(width 0.1)
				(type default)
			)
			(layer "B.Fab")
		)
		(fp_line
			(start 0.12065 -0.305054)
			(end 0.12065 -0.2794)
			(stroke
				(width 0.1)
				(type default)
			)
			(layer "B.Fab")
		)
		(fp_line
			(start 0.12065 -0.2794)
			(end -0.12065 -0.2794)
			(stroke
				(width 0.1)
				(type default)
			)
			(layer "B.Fab")
		)
		(fp_line
			(start 0.12065 0.2794)
			(end 0.12065 0.3048)
			(stroke
				(width 0.1)
				(type default)
			)
			(layer "B.Fab")
		)
		(fp_line
			(start 0.12065 0.3048)
			(end 0.67945 0.3048)
			(stroke
				(width 0.1)
				(type default)
			)
			(layer "B.Fab")
		)
		(fp_line
			(start 0.67945 -0.305054)
			(end 0.12065 -0.305054)
			(stroke
				(width 0.1)
				(type default)
			)
			(layer "B.Fab")
		)
		(fp_line
			(start 0.67945 0.3048)
			(end 0.67945 -0.305054)
			(stroke
				(width 0.1)
				(type default)
			)
			(layer "B.Fab")
		)
		(pad "1" smd circle
			(at 0.40005 0 180)
			(size 0 0)
			(layers "B.Cu" "B.Mask" "B.Paste")
			(net "P1V8_AUX")
		)
		(pad "2" smd circle
			(at -0.40005 0 180)
			(size 0 0)
			(layers "B.Cu" "B.Mask" "B.Paste")
			(net "GND")
		)
	)
	(footprint ""
		(layer "B.Cu")
		(at 349.118682 -398.942052 90)
		(property "Reference" "C644"
			(at 0 0 90)
			(layer "B.SilkS")
			(hide yes)
			(effects
				(font
					(size 1.27 1.27)
				)
				(justify mirror)
			)
		)
		(property "Value" ""
			(at 0 0 90)
			(layer "B.Fab")
			(effects
				(font
					(size 1.27 1.27)
				)
				(justify mirror)
			)
		)
		(duplicate_pad_numbers_are_jumpers no)
		(fp_line
			(start 0.7874 -0.4064)
			(end -0.7874 -0.4064)
			(stroke
				(width 0.1524)
				(type default)
			)
			(layer "B.SilkS")
		)
		(fp_line
			(start -0.7874 -0.4064)
			(end -0.7874 0.4064)
			(stroke
				(width 0.1524)
				(type default)
			)
			(layer "B.SilkS")
		)
		(fp_line
			(start 0.7874 0.4064)
			(end 0.7874 -0.4064)
			(stroke
				(width 0.1524)
				(type default)
			)
			(layer "B.SilkS")
		)
		(fp_line
			(start -0.7874 0.4064)
			(end 0.7874 0.4064)
			(stroke
				(width 0.1524)
				(type default)
			)
			(layer "B.SilkS")
		)
		(fp_line
			(start 0.67945 -0.305054)
			(end 0.12065 -0.305054)
			(stroke
				(width 0.1)
				(type default)
			)
			(layer "B.Fab")
		)
		(fp_line
			(start 0.12065 -0.305054)
			(end 0.12065 -0.2794)
			(stroke
				(width 0.1)
				(type default)
			)
			(layer "B.Fab")
		)
		(fp_line
			(start -0.12065 -0.3048)
			(end -0.67945 -0.3048)
			(stroke
				(width 0.1)
				(type default)
			)
			(layer "B.Fab")
		)
		(fp_line
			(start -0.67945 -0.3048)
			(end -0.67945 0.3048)
			(stroke
				(width 0.1)
				(type default)
			)
			(layer "B.Fab")
		)
		(fp_line
			(start 0.12065 -0.2794)
			(end -0.12065 -0.2794)
			(stroke
				(width 0.1)
				(type default)
			)
			(layer "B.Fab")
		)
		(fp_line
			(start -0.12065 -0.2794)
			(end -0.12065 -0.3048)
			(stroke
				(width 0.1)
				(type default)
			)
			(layer "B.Fab")
		)
		(fp_line
			(start 0.12065 0.2794)
			(end 0.12065 0.3048)
			(stroke
				(width 0.1)
				(type default)
			)
			(layer "B.Fab")
		)
		(fp_line
			(start -0.120396 0.2794)
			(end 0.12065 0.2794)
			(stroke
				(width 0.1)
				(type default)
			)
			(layer "B.Fab")
		)
		(fp_line
			(start 0.67945 0.3048)
			(end 0.67945 -0.305054)
			(stroke
				(width 0.1)
				(type default)
			)
			(layer "B.Fab")
		)
		(fp_line
			(start 0.12065 0.3048)
			(end 0.67945 0.3048)
			(stroke
				(width 0.1)
				(type default)
			)
			(layer "B.Fab")
		)
		(fp_line
			(start -0.120396 0.3048)
			(end -0.120396 0.2794)
			(stroke
				(width 0.1)
				(type default)
			)
			(layer "B.Fab")
		)
		(fp_line
			(start -0.67945 0.3048)
			(end -0.120396 0.3048)
			(stroke
				(width 0.1)
				(type default)
			)
			(layer "B.Fab")
		)
		(pad "1" smd circle
			(at 0.40005 0 270)
			(size 0 0)
			(layers "B.Cu" "B.Mask" "B.Paste")
			(net "P0V9_CPU0_RT1_2A")
		)
		(pad "2" smd circle
			(at -0.40005 0 270)
			(size 0 0)
			(layers "B.Cu" "B.Mask" "B.Paste")
			(net "GND")
		)
	)
)
